(kicad_pcb
	(version 20260206)
	(generator "pcbnew")
	(generator_version "10.0")
	(general
		(thickness 1.6)
		(legacy_teardrops no)
	)
	(paper "A4")
	(title_block
		(title "03242023_DA0F0TMBIJ0_F0T_Motherboard_J_brd_V01_OCP.brd")
		(comment 1 "Grand Teton / footprint 2856 of 6105 (J2), pads 113-224 of 291")
	)
	(layers
		(0 "F.Cu" signal "TOP")
		(4 "In1.Cu" signal "GND")
		(6 "In2.Cu" signal "IN1")
		(8 "In3.Cu" signal "GND1")
		(10 "In4.Cu" signal "IN2")
		(12 "In5.Cu" signal "GND2")
		(14 "In6.Cu" signal "IN3")
		(16 "In7.Cu" signal "GND3")
		(18 "In8.Cu" signal "VCC")
		(20 "In9.Cu" signal "VCC1")
		(22 "In10.Cu" signal "GND4")
		(24 "In11.Cu" signal "IN4")
		(26 "In12.Cu" signal "GND5")
		(28 "In13.Cu" signal "IN5")
		(30 "In14.Cu" signal "GND6")
		(32 "In15.Cu" signal "IN6")
		(34 "In16.Cu" signal "GND7")
		(2 "B.Cu" signal "BOTTOM")
		(9 "F.Adhes" user "F.Adhesive")
		(11 "B.Adhes" user "B.Adhesive")
		(13 "F.Paste" user "Package Geometry/Pastemask Top")
		(15 "B.Paste" user "Package Geometry/Pastemask Bottom")
		(5 "F.SilkS" user "Ref Des/Silkscreen Top")
		(7 "B.SilkS" user "Ref Des/Silkscreen Bottom")
		(1 "F.Mask" user "Board Geometry/Soldermask Top")
		(3 "B.Mask" user "Board Geometry/Soldermask Bottom")
		(17 "Dwgs.User" user "User.Drawings")
		(19 "Cmts.User" user "User.Comments")
		(21 "Eco1.User" user "User.Eco1")
		(23 "Eco2.User" user "User.Eco2")
		(25 "Edge.Cuts" user "Board Geometry/Outline")
		(27 "Margin" user)
		(31 "F.CrtYd" user "Package Geometry/Place Bound Top")
		(29 "B.CrtYd" user "Package Geometry/Place Bound Bottom")
		(35 "F.Fab" user "Ref Des/Assembly Top")
		(33 "B.Fab" user "Ref Des/Assembly Bottom")
	)
	(footprint ""
		(layer "F.Cu")
		(at 310.937148 -258.091686)
		(property "Reference" "J2"
			(at -3.683 -81.702148 0)
			(unlocked yes)
			(layer "F.SilkS")
			(effects
				(font
					(size 0.7874 0.5842)
					(thickness 0.1524)
				)
				(justify left)
			)
		)
		(property "Value" ""
			(at 0 0 0)
			(layer "F.Fab")
			(effects
				(font
					(size 1.27 1.27)
				)
			)
		)
		(duplicate_pad_numbers_are_jumpers no)
		(pad "113" smd rect
			(at -2.050034 36.975034 270)
			(size 0.519938 1.4986)
			(layers "F.Cu" "F.Mask" "F.Paste")
			(net "M_A_CPU0_SB_DQ<9>")
		)
		(pad "114" smd rect
			(at -2.050034 37.824918 270)
			(size 0.519938 1.4986)
			(layers "F.Cu" "F.Mask" "F.Paste")
			(net "GND")
		)
		(pad "115" smd rect
			(at -2.050034 38.675056 270)
			(size 0.519938 1.4986)
			(layers "F.Cu" "F.Mask" "F.Paste")
			(net "M_A_CPU0_SB_DQS_DP<1>")
		)
		(pad "116" smd rect
			(at -2.050034 39.52494 270)
			(size 0.519938 1.4986)
			(layers "F.Cu" "F.Mask" "F.Paste")
			(net "M_A_CPU0_SB_DQS_DN<1>")
		)
		(pad "117" smd rect
			(at -2.050034 40.375078 270)
			(size 0.519938 1.4986)
			(layers "F.Cu" "F.Mask" "F.Paste")
			(net "GND")
		)
		(pad "118" smd rect
			(at -2.050034 41.224962 270)
			(size 0.519938 1.4986)
			(layers "F.Cu" "F.Mask" "F.Paste")
			(net "M_A_CPU0_SB_DQ<12>")
		)
		(pad "119" smd rect
			(at -2.050034 42.0751 270)
			(size 0.519938 1.4986)
			(layers "F.Cu" "F.Mask" "F.Paste")
			(net "GND")
		)
		(pad "120" smd rect
			(at -2.050034 42.924984 270)
			(size 0.519938 1.4986)
			(layers "F.Cu" "F.Mask" "F.Paste")
			(net "M_A_CPU0_SB_DQ<13>")
		)
		(pad "121" smd rect
			(at -2.050034 43.775122 270)
			(size 0.519938 1.4986)
			(layers "F.Cu" "F.Mask" "F.Paste")
			(net "GND")
		)
		(pad "122" smd rect
			(at -2.050034 44.625006 270)
			(size 0.519938 1.4986)
			(layers "F.Cu" "F.Mask" "F.Paste")
			(net "M_A_CPU0_SB_DQ<16>")
		)
		(pad "123" smd rect
			(at -2.050034 45.47489 270)
			(size 0.519938 1.4986)
			(layers "F.Cu" "F.Mask" "F.Paste")
			(net "GND")
		)
		(pad "124" smd rect
			(at -2.050034 46.325028 270)
			(size 0.519938 1.4986)
			(layers "F.Cu" "F.Mask" "F.Paste")
			(net "M_A_CPU0_SB_DQ<17>")
		)
		(pad "125" smd rect
			(at -2.050034 47.174912 270)
			(size 0.519938 1.4986)
			(layers "F.Cu" "F.Mask" "F.Paste")
			(net "GND")
		)
		(pad "126" smd rect
			(at -2.050034 48.02505 270)
			(size 0.519938 1.4986)
			(layers "F.Cu" "F.Mask" "F.Paste")
			(net "M_A_CPU0_SB_DQS_DP<2>")
		)
		(pad "127" smd rect
			(at -2.050034 48.874934 270)
			(size 0.519938 1.4986)
			(layers "F.Cu" "F.Mask" "F.Paste")
			(net "M_A_CPU0_SB_DQS_DN<2>")
		)
		(pad "128" smd rect
			(at -2.050034 49.725072 270)
			(size 0.519938 1.4986)
			(layers "F.Cu" "F.Mask" "F.Paste")
			(net "GND")
		)
		(pad "129" smd rect
			(at -2.050034 50.574956 270)
			(size 0.519938 1.4986)
			(layers "F.Cu" "F.Mask" "F.Paste")
			(net "M_A_CPU0_SB_DQ<20>")
		)
		(pad "130" smd rect
			(at -2.050034 51.425094 270)
			(size 0.519938 1.4986)
			(layers "F.Cu" "F.Mask" "F.Paste")
			(net "GND")
		)
		(pad "131" smd rect
			(at -2.050034 52.274978 270)
			(size 0.519938 1.4986)
			(layers "F.Cu" "F.Mask" "F.Paste")
			(net "M_A_CPU0_SB_DQ<21>")
		)
		(pad "132" smd rect
			(at -2.050034 53.125116 270)
			(size 0.519938 1.4986)
			(layers "F.Cu" "F.Mask" "F.Paste")
			(net "GND")
		)
		(pad "133" smd rect
			(at -2.050034 53.975 270)
			(size 0.519938 1.4986)
			(layers "F.Cu" "F.Mask" "F.Paste")
			(net "M_A_CPU0_SB_DQ<24>")
		)
		(pad "134" smd rect
			(at -2.050034 54.824884 270)
			(size 0.519938 1.4986)
			(layers "F.Cu" "F.Mask" "F.Paste")
			(net "GND")
		)
		(pad "135" smd rect
			(at -2.050034 55.675022 270)
			(size 0.519938 1.4986)
			(layers "F.Cu" "F.Mask" "F.Paste")
			(net "M_A_CPU0_SB_DQ<25>")
		)
		(pad "136" smd rect
			(at -2.050034 56.524906 270)
			(size 0.519938 1.4986)
			(layers "F.Cu" "F.Mask" "F.Paste")
			(net "GND")
		)
		(pad "137" smd rect
			(at -2.050034 57.375044 270)
			(size 0.519938 1.4986)
			(layers "F.Cu" "F.Mask" "F.Paste")
			(net "M_A_CPU0_SB_DQS_DP<3>")
		)
		(pad "138" smd rect
			(at -2.050034 58.224928 270)
			(size 0.519938 1.4986)
			(layers "F.Cu" "F.Mask" "F.Paste")
			(net "M_A_CPU0_SB_DQS_DN<3>")
		)
		(pad "139" smd rect
			(at -2.050034 59.075066 270)
			(size 0.519938 1.4986)
			(layers "F.Cu" "F.Mask" "F.Paste")
			(net "GND")
		)
		(pad "140" smd rect
			(at -2.050034 59.92495 270)
			(size 0.519938 1.4986)
			(layers "F.Cu" "F.Mask" "F.Paste")
			(net "M_A_CPU0_SB_DQ<28>")
		)
		(pad "141" smd rect
			(at -2.050034 60.775088 270)
			(size 0.519938 1.4986)
			(layers "F.Cu" "F.Mask" "F.Paste")
			(net "GND")
		)
		(pad "142" smd rect
			(at -2.050034 61.624972 270)
			(size 0.519938 1.4986)
			(layers "F.Cu" "F.Mask" "F.Paste")
			(net "M_A_CPU0_SB_DQ<29>")
		)
		(pad "143" smd rect
			(at -2.050034 62.47511 270)
			(size 0.519938 1.4986)
			(layers "F.Cu" "F.Mask" "F.Paste")
			(net "GND")
		)
		(pad "144" smd rect
			(at -2.050034 63.324994 270)
			(size 0.519938 1.4986)
			(layers "F.Cu" "F.Mask" "F.Paste")
			(net "TP_CHA_CPU0_DIMM2_FRU_1")
		)
		(pad "145" smd rect
			(at 2.050034 -63.324994 270)
			(size 0.519938 1.4986)
			(layers "F.Cu" "F.Mask" "F.Paste")
			(net "P12V_S3_AUX_CPU0_NVDIMM")
		)
		(pad "146" smd rect
			(at 2.050034 -62.47511 270)
			(size 0.519938 1.4986)
			(layers "F.Cu" "F.Mask" "F.Paste")
			(net "P12V_S3_AUX_CPU0_NVDIMM")
		)
		(pad "147" smd rect
			(at 2.050034 -61.624972 270)
			(size 0.519938 1.4986)
			(layers "F.Cu" "F.Mask" "F.Paste")
			(net "PWRGD_CHA_CPU0_DIMM2")
		)
		(pad "148" smd rect
			(at 2.050034 -60.775088 270)
			(size 0.519938 1.4986)
			(layers "F.Cu" "F.Mask" "F.Paste")
			(net "PD_CHA_CPU0_DIMM2_SAA")
		)
		(pad "149" smd rect
			(at 2.050034 -59.92495 270)
			(size 0.519938 1.4986)
			(layers "F.Cu" "F.Mask" "F.Paste")
			(net "TP_CHA_CPU0_DIMM2_FRU_2")
		)
		(pad "150" smd rect
			(at 2.050034 -59.075066 270)
			(size 0.519938 1.4986)
			(layers "F.Cu" "F.Mask" "F.Paste")
			(net "TP_CHA_CPU0_DIMM2_FRU_3")
		)
		(pad "151" smd rect
			(at 2.050034 -58.224928 270)
			(size 0.519938 1.4986)
			(layers "F.Cu" "F.Mask" "F.Paste")
			(net "GND")
		)
		(pad "152" smd rect
			(at 2.050034 -57.375044 270)
			(size 0.519938 1.4986)
			(layers "F.Cu" "F.Mask" "F.Paste")
			(net "M_A_CPU0_SA_DQ<2>")
		)
		(pad "153" smd rect
			(at 2.050034 -56.524906 270)
			(size 0.519938 1.4986)
			(layers "F.Cu" "F.Mask" "F.Paste")
			(net "GND")
		)
		(pad "154" smd rect
			(at 2.050034 -55.675022 270)
			(size 0.519938 1.4986)
			(layers "F.Cu" "F.Mask" "F.Paste")
			(net "M_A_CPU0_SA_DQ<3>")
		)
		(pad "155" smd rect
			(at 2.050034 -54.824884 270)
			(size 0.519938 1.4986)
			(layers "F.Cu" "F.Mask" "F.Paste")
			(net "GND")
		)
		(pad "156" smd rect
			(at 2.050034 -53.975 270)
			(size 0.519938 1.4986)
			(layers "F.Cu" "F.Mask" "F.Paste")
			(net "M_A_CPU0_SA_DQS_DN<5>")
		)
		(pad "157" smd rect
			(at 2.050034 -53.125116 270)
			(size 0.519938 1.4986)
			(layers "F.Cu" "F.Mask" "F.Paste")
			(net "M_A_CPU0_SA_DQS_DP<5>")
		)
		(pad "158" smd rect
			(at 2.050034 -52.274978 270)
			(size 0.519938 1.4986)
			(layers "F.Cu" "F.Mask" "F.Paste")
			(net "GND")
		)
		(pad "159" smd rect
			(at 2.050034 -51.425094 270)
			(size 0.519938 1.4986)
			(layers "F.Cu" "F.Mask" "F.Paste")
			(net "M_A_CPU0_SA_DQ<6>")
		)
		(pad "160" smd rect
			(at 2.050034 -50.574956 270)
			(size 0.519938 1.4986)
			(layers "F.Cu" "F.Mask" "F.Paste")
			(net "GND")
		)
		(pad "161" smd rect
			(at 2.050034 -49.725072 270)
			(size 0.519938 1.4986)
			(layers "F.Cu" "F.Mask" "F.Paste")
			(net "M_A_CPU0_SA_DQ<7>")
		)
		(pad "162" smd rect
			(at 2.050034 -48.874934 270)
			(size 0.519938 1.4986)
			(layers "F.Cu" "F.Mask" "F.Paste")
			(net "GND")
		)
		(pad "163" smd rect
			(at 2.050034 -48.02505 270)
			(size 0.519938 1.4986)
			(layers "F.Cu" "F.Mask" "F.Paste")
			(net "M_A_CPU0_SA_DQ<10>")
		)
		(pad "164" smd rect
			(at 2.050034 -47.174912 270)
			(size 0.519938 1.4986)
			(layers "F.Cu" "F.Mask" "F.Paste")
			(net "GND")
		)
		(pad "165" smd rect
			(at 2.050034 -46.325028 270)
			(size 0.519938 1.4986)
			(layers "F.Cu" "F.Mask" "F.Paste")
			(net "M_A_CPU0_SA_DQ<11>")
		)
		(pad "166" smd rect
			(at 2.050034 -45.47489 270)
			(size 0.519938 1.4986)
			(layers "F.Cu" "F.Mask" "F.Paste")
			(net "GND")
		)
		(pad "167" smd rect
			(at 2.050034 -44.625006 270)
			(size 0.519938 1.4986)
			(layers "F.Cu" "F.Mask" "F.Paste")
			(net "M_A_CPU0_SA_DQS_DN<6>")
		)
		(pad "168" smd rect
			(at 2.050034 -43.775122 270)
			(size 0.519938 1.4986)
			(layers "F.Cu" "F.Mask" "F.Paste")
			(net "M_A_CPU0_SA_DQS_DP<6>")
		)
		(pad "169" smd rect
			(at 2.050034 -42.924984 270)
			(size 0.519938 1.4986)
			(layers "F.Cu" "F.Mask" "F.Paste")
			(net "GND")
		)
		(pad "170" smd rect
			(at 2.050034 -42.0751 270)
			(size 0.519938 1.4986)
			(layers "F.Cu" "F.Mask" "F.Paste")
			(net "M_A_CPU0_SA_DQ<14>")
		)
		(pad "171" smd rect
			(at 2.050034 -41.224962 270)
			(size 0.519938 1.4986)
			(layers "F.Cu" "F.Mask" "F.Paste")
			(net "GND")
		)
		(pad "172" smd rect
			(at 2.050034 -40.375078 270)
			(size 0.519938 1.4986)
			(layers "F.Cu" "F.Mask" "F.Paste")
			(net "M_A_CPU0_SA_DQ<15>")
		)
		(pad "173" smd rect
			(at 2.050034 -39.52494 270)
			(size 0.519938 1.4986)
			(layers "F.Cu" "F.Mask" "F.Paste")
			(net "GND")
		)
		(pad "174" smd rect
			(at 2.050034 -38.675056 270)
			(size 0.519938 1.4986)
			(layers "F.Cu" "F.Mask" "F.Paste")
			(net "M_A_CPU0_SA_DQ<18>")
		)
		(pad "175" smd rect
			(at 2.050034 -37.824918 270)
			(size 0.519938 1.4986)
			(layers "F.Cu" "F.Mask" "F.Paste")
			(net "GND")
		)
		(pad "176" smd rect
			(at 2.050034 -36.975034 270)
			(size 0.519938 1.4986)
			(layers "F.Cu" "F.Mask" "F.Paste")
			(net "M_A_CPU0_SA_DQ<19>")
		)
		(pad "177" smd rect
			(at 2.050034 -36.124896 270)
			(size 0.519938 1.4986)
			(layers "F.Cu" "F.Mask" "F.Paste")
			(net "GND")
		)
		(pad "178" smd rect
			(at 2.050034 -35.275012 270)
			(size 0.519938 1.4986)
			(layers "F.Cu" "F.Mask" "F.Paste")
			(net "M_A_CPU0_SA_DQS_DN<7>")
		)
		(pad "179" smd rect
			(at 2.050034 -34.425128 270)
			(size 0.519938 1.4986)
			(layers "F.Cu" "F.Mask" "F.Paste")
			(net "M_A_CPU0_SA_DQS_DP<7>")
		)
		(pad "180" smd rect
			(at 2.050034 -33.57499 270)
			(size 0.519938 1.4986)
			(layers "F.Cu" "F.Mask" "F.Paste")
			(net "GND")
		)
		(pad "181" smd rect
			(at 2.050034 -32.725106 270)
			(size 0.519938 1.4986)
			(layers "F.Cu" "F.Mask" "F.Paste")
			(net "M_A_CPU0_SA_DQ<22>")
		)
		(pad "182" smd rect
			(at 2.050034 -31.874968 270)
			(size 0.519938 1.4986)
			(layers "F.Cu" "F.Mask" "F.Paste")
			(net "GND")
		)
		(pad "183" smd rect
			(at 2.050034 -31.025084 270)
			(size 0.519938 1.4986)
			(layers "F.Cu" "F.Mask" "F.Paste")
			(net "M_A_CPU0_SA_DQ<23>")
		)
		(pad "184" smd rect
			(at 2.050034 -30.174946 270)
			(size 0.519938 1.4986)
			(layers "F.Cu" "F.Mask" "F.Paste")
			(net "GND")
		)
		(pad "185" smd rect
			(at 2.050034 -29.325062 270)
			(size 0.519938 1.4986)
			(layers "F.Cu" "F.Mask" "F.Paste")
			(net "M_A_CPU0_SA_DQ<26>")
		)
		(pad "186" smd rect
			(at 2.050034 -28.474924 270)
			(size 0.519938 1.4986)
			(layers "F.Cu" "F.Mask" "F.Paste")
			(net "GND")
		)
		(pad "187" smd rect
			(at 2.050034 -27.62504 270)
			(size 0.519938 1.4986)
			(layers "F.Cu" "F.Mask" "F.Paste")
			(net "M_A_CPU0_SA_DQ<27>")
		)
		(pad "188" smd rect
			(at 2.050034 -26.774902 270)
			(size 0.519938 1.4986)
			(layers "F.Cu" "F.Mask" "F.Paste")
			(net "GND")
		)
		(pad "189" smd rect
			(at 2.050034 -25.925018 270)
			(size 0.519938 1.4986)
			(layers "F.Cu" "F.Mask" "F.Paste")
			(net "M_A_CPU0_SA_DQS_DN<8>")
		)
		(pad "190" smd rect
			(at 2.050034 -25.07488 270)
			(size 0.519938 1.4986)
			(layers "F.Cu" "F.Mask" "F.Paste")
			(net "M_A_CPU0_SA_DQS_DP<8>")
		)
		(pad "191" smd rect
			(at 2.050034 -24.224996 270)
			(size 0.519938 1.4986)
			(layers "F.Cu" "F.Mask" "F.Paste")
			(net "GND")
		)
		(pad "192" smd rect
			(at 2.050034 -23.375112 270)
			(size 0.519938 1.4986)
			(layers "F.Cu" "F.Mask" "F.Paste")
			(net "M_A_CPU0_SA_DQ<30>")
		)
		(pad "193" smd rect
			(at 2.050034 -22.524974 270)
			(size 0.519938 1.4986)
			(layers "F.Cu" "F.Mask" "F.Paste")
			(net "GND")
		)
		(pad "194" smd rect
			(at 2.050034 -21.67509 270)
			(size 0.519938 1.4986)
			(layers "F.Cu" "F.Mask" "F.Paste")
			(net "M_A_CPU0_SA_DQ<31>")
		)
		(pad "195" smd rect
			(at 2.050034 -20.824952 270)
			(size 0.519938 1.4986)
			(layers "F.Cu" "F.Mask" "F.Paste")
			(net "GND")
		)
		(pad "196" smd rect
			(at 2.050034 -19.975068 270)
			(size 0.519938 1.4986)
			(layers "F.Cu" "F.Mask" "F.Paste")
			(net "M_A_CPU0_SA_CB<2>")
		)
		(pad "197" smd rect
			(at 2.050034 -19.12493 270)
			(size 0.519938 1.4986)
			(layers "F.Cu" "F.Mask" "F.Paste")
			(net "GND")
		)
		(pad "198" smd rect
			(at 2.050034 -18.275046 270)
			(size 0.519938 1.4986)
			(layers "F.Cu" "F.Mask" "F.Paste")
			(net "M_A_CPU0_SA_CB<3>")
		)
		(pad "199" smd rect
			(at 2.050034 -17.424908 270)
			(size 0.519938 1.4986)
			(layers "F.Cu" "F.Mask" "F.Paste")
			(net "GND")
		)
		(pad "200" smd rect
			(at 2.050034 -16.575024 270)
			(size 0.519938 1.4986)
			(layers "F.Cu" "F.Mask" "F.Paste")
			(net "M_A_CPU0_SA_DQS_DN<9>")
		)
		(pad "201" smd rect
			(at 2.050034 -15.724886 270)
			(size 0.519938 1.4986)
			(layers "F.Cu" "F.Mask" "F.Paste")
			(net "M_A_CPU0_SA_DQS_DP<9>")
		)
		(pad "202" smd rect
			(at 2.050034 -14.875002 270)
			(size 0.519938 1.4986)
			(layers "F.Cu" "F.Mask" "F.Paste")
			(net "GND")
		)
		(pad "203" smd rect
			(at 2.050034 -14.025118 270)
			(size 0.519938 1.4986)
			(layers "F.Cu" "F.Mask" "F.Paste")
			(net "M_A_CPU0_SA_CB<6>")
		)
		(pad "204" smd rect
			(at 2.050034 -13.17498 270)
			(size 0.519938 1.4986)
			(layers "F.Cu" "F.Mask" "F.Paste")
			(net "GND")
		)
		(pad "205" smd rect
			(at 2.050034 -12.325096 270)
			(size 0.519938 1.4986)
			(layers "F.Cu" "F.Mask" "F.Paste")
			(net "M_A_CPU0_SA_CB<7>")
		)
		(pad "206" smd rect
			(at 2.050034 -11.474958 270)
			(size 0.519938 1.4986)
			(layers "F.Cu" "F.Mask" "F.Paste")
			(net "GND")
		)
		(pad "207" smd rect
			(at 2.050034 -10.625074 270)
			(size 0.519938 1.4986)
			(layers "F.Cu" "F.Mask" "F.Paste")
			(net "RST_M_AB_CPU0_FPGA_N")
		)
		(pad "208" smd rect
			(at 2.050034 -9.774936 270)
			(size 0.519938 1.4986)
			(layers "F.Cu" "F.Mask" "F.Paste")
			(net "GND")
		)
		(pad "209" smd rect
			(at 2.050034 -8.925052 270)
			(size 0.519938 1.4986)
			(layers "F.Cu" "F.Mask" "F.Paste")
			(net "M_A_CPU0_SA_CS_N<3>")
		)
		(pad "210" smd rect
			(at 2.050034 -8.074914 270)
			(size 0.519938 1.4986)
			(layers "F.Cu" "F.Mask" "F.Paste")
			(net "GND")
		)
		(pad "211" smd rect
			(at 2.050034 -7.22503 270)
			(size 0.519938 1.4986)
			(layers "F.Cu" "F.Mask" "F.Paste")
			(net "M_A_CPU0_SA_CA<1>")
		)
		(pad "212" smd rect
			(at 2.050034 -6.374892 270)
			(size 0.519938 1.4986)
			(layers "F.Cu" "F.Mask" "F.Paste")
			(net "GND")
		)
		(pad "213" smd rect
			(at 2.050034 -5.525008 270)
			(size 0.519938 1.4986)
			(layers "F.Cu" "F.Mask" "F.Paste")
			(net "M_A_CPU0_SA_CA<3>")
		)
		(pad "214" smd rect
			(at 2.050034 -4.675124 270)
			(size 0.519938 1.4986)
			(layers "F.Cu" "F.Mask" "F.Paste")
			(net "GND")
		)
		(pad "215" smd rect
			(at 2.050034 -3.824986 270)
			(size 0.519938 1.4986)
			(layers "F.Cu" "F.Mask" "F.Paste")
			(net "M_A_CPU0_SA_CA<5>")
		)
		(pad "216" smd rect
			(at 2.050034 -2.975102 270)
			(size 0.519938 1.4986)
			(layers "F.Cu" "F.Mask" "F.Paste")
			(net "GND")
		)
		(pad "217" smd rect
			(at 2.050034 -2.124964 270)
			(size 0.519938 1.4986)
			(layers "F.Cu" "F.Mask" "F.Paste")
			(net "M_A_CPU0_CLK_DP<1>")
		)
		(pad "218" smd rect
			(at 2.050034 -1.27508 270)
			(size 0.519938 1.4986)
			(layers "F.Cu" "F.Mask" "F.Paste")
			(net "M_A_CPU0_CLK_DN<1>")
		)
		(pad "219" smd rect
			(at 2.050034 -0.424942 270)
			(size 0.519938 1.4986)
			(layers "F.Cu" "F.Mask" "F.Paste")
			(net "GND")
		)
		(pad "220" smd rect
			(at 2.050034 5.525008 270)
			(size 0.519938 1.4986)
			(layers "F.Cu" "F.Mask" "F.Paste")
			(net "TP_CHA_CPU0_DIMM2_FRU_4")
		)
		(pad "221" smd rect
			(at 2.050034 6.374892 270)
			(size 0.519938 1.4986)
			(layers "F.Cu" "F.Mask" "F.Paste")
			(net "M_A_CPU0_SB_CA<1>")
		)
		(pad "222" smd rect
			(at 2.050034 7.22503 270)
			(size 0.519938 1.4986)
			(layers "F.Cu" "F.Mask" "F.Paste")
			(net "GND")
		)
		(pad "223" smd rect
			(at 2.050034 8.074914 270)
			(size 0.519938 1.4986)
			(layers "F.Cu" "F.Mask" "F.Paste")
			(net "M_A_CPU0_SB_CA<3>")
		)
		(pad "224" smd rect
			(at 2.050034 8.925052 270)
			(size 0.519938 1.4986)
			(layers "F.Cu" "F.Mask" "F.Paste")
			(net "GND")
		)
	)
)
